# T6G (Grand Teton) — schematic netlist excerpt (pin names and nets, part order shuffled) for the footprints in the layout excerpt that follows; sources: Cadence DE-HDL packaged netlist, KiCad conversion of 04192023_DAF0TMB3IC0_F0TG_MB_C_brd_V02_OCP.brd

DB2  TDR_3P  EMPTY  pkg TH2  page 260
  GND  = T1_GND
  IO1  = TDR_SE_45_OHM_IN1
  IO2  = TDR_SE_45_OHM_IN1

PC353  Q_CAP  0.22UF 16V 10% X7R  pkg 0402  page 216 : A = SW_PVDDCR_SOC_P1_BOOT3_RC ; B = SW_PVDDCR_SOC_P1_PH3
PL6512  Q_INDUCTOR  120NH/69A IND  pkg SMLF  page 365 : \1\ = SW_P0V9_RETIMER_CPU1_SW2 ; \2\ = P0V9_CPU1_RT_2D

(kicad_pcb
	(version 20260206)
	(generator "pcbnew")
	(generator_version "10.0")
	(general
		(thickness 1.6)
		(legacy_teardrops no)
	)
	(paper "A4")
	(title_block
		(title "04192023_DAF0TMB3IC0_F0TG_MB_C_brd_V02_OCP.brd")
		(comment 1 "Grand Teton / footprints 2077-2079 of 8354")
	)
	(layers
		(0 "F.Cu" signal "TOP")
		(4 "In1.Cu" signal "GND")
		(6 "In2.Cu" signal "IN1")
		(8 "In3.Cu" signal "GND1")
		(10 "In4.Cu" signal "IN2")
		(12 "In5.Cu" signal "GND2")
		(14 "In6.Cu" signal "IN3")
		(16 "In7.Cu" signal "GND3")
		(18 "In8.Cu" signal "VCC")
		(20 "In9.Cu" signal "VCC1")
		(22 "In10.Cu" signal "GND4")
		(24 "In11.Cu" signal "IN4")
		(26 "In12.Cu" signal "GND5")
		(28 "In13.Cu" signal "IN5")
		(30 "In14.Cu" signal "GND6")
		(32 "In15.Cu" signal "IN6")
		(34 "In16.Cu" signal "GND7")
		(2 "B.Cu" signal "BOTTOM")
		(9 "F.Adhes" user "F.Adhesive")
		(11 "B.Adhes" user "B.Adhesive")
		(13 "F.Paste" user "Package Geometry/Pastemask Top")
		(15 "B.Paste" user "Package Geometry/Pastemask Bottom")
		(5 "F.SilkS" user "Ref Des/Silkscreen Top")
		(7 "B.SilkS" user "Ref Des/Silkscreen Bottom")
		(1 "F.Mask" user "Board Geometry/Soldermask Top")
		(3 "B.Mask" user "Board Geometry/Soldermask Bottom")
		(17 "Dwgs.User" user "User.Drawings")
		(19 "Cmts.User" user "User.Comments")
		(21 "Eco1.User" user "User.Eco1")
		(23 "Eco2.User" user "User.Eco2")
		(25 "Edge.Cuts" user "Board Geometry/Outline")
		(27 "Margin" user)
		(31 "F.CrtYd" user "Package Geometry/Place Bound Top")
		(29 "B.CrtYd" user "Package Geometry/Place Bound Bottom")
		(35 "F.Fab" user "Ref Des/Assembly Top")
		(33 "B.Fab" user "Ref Des/Assembly Bottom")
	)
	(footprint ""
		(layer "F.Cu")
		(at 25.322784 -381.6858 -90)
		(property "Reference" "PL6512"
			(at 3.2258 -4.167886 90)
			(unlocked yes)
			(layer "F.SilkS")
			(effects
				(font
					(size 0.7874 0.5842)
					(thickness 0.1524)
				)
				(justify left)
			)
		)
		(property "Value" ""
			(at 0 0 270)
			(layer "F.Fab")
			(effects
				(font
					(size 1.27 1.27)
				)
			)
		)
		(duplicate_pad_numbers_are_jumpers no)
		(fp_line
			(start -3.24993 3.24993)
			(end -3.24993 2.2352)
			(stroke
				(width 0.1524)
				(type default)
			)
			(layer "F.SilkS")
		)
		(fp_line
			(start 3.24993 3.24993)
			(end -3.24993 3.24993)
			(stroke
				(width 0.1524)
				(type default)
			)
			(layer "F.SilkS")
		)
		(fp_line
			(start 3.24993 2.2352)
			(end 3.24993 3.24993)
			(stroke
				(width 0.1524)
				(type default)
			)
			(layer "F.SilkS")
		)
		(fp_line
			(start -3.24993 -2.2352)
			(end -3.24993 -3.24993)
			(stroke
				(width 0.1524)
				(type default)
			)
			(layer "F.SilkS")
		)
		(fp_line
			(start -3.24993 -3.24993)
			(end 3.24993 -3.24993)
			(stroke
				(width 0.1524)
				(type default)
			)
			(layer "F.SilkS")
		)
		(fp_line
			(start 3.24993 -3.24993)
			(end 3.24993 -2.2352)
			(stroke
				(width 0.1524)
				(type default)
			)
			(layer "F.SilkS")
		)
		(fp_line
			(start -3.24993 3.24993)
			(end -3.24993 -3.24993)
			(stroke
				(width 0.1)
				(type default)
			)
			(layer "F.Fab")
		)
		(fp_line
			(start 3.24993 3.24993)
			(end -3.24993 3.24993)
			(stroke
				(width 0.1)
				(type default)
			)
			(layer "F.Fab")
		)
		(fp_line
			(start -3.24993 -3.24993)
			(end 3.24993 -3.24993)
			(stroke
				(width 0.1)
				(type default)
			)
			(layer "F.Fab")
		)
		(fp_line
			(start 3.24993 -3.24993)
			(end 3.24993 3.24993)
			(stroke
				(width 0.1)
				(type default)
			)
			(layer "F.Fab")
		)
		(pad "1" smd rect
			(at -2.29997 0 270)
			(size 2.0066 4.2164)
			(layers "F.Cu" "F.Mask" "F.Paste")
			(net "SW_P0V9_RETIMER_CPU1_SW2")
		)
		(pad "2" smd rect
			(at 2.29997 0 270)
			(size 2.0066 4.2164)
			(layers "F.Cu" "F.Mask" "F.Paste")
			(net "P0V9_CPU1_RT_2D")
		)
	)
	(footprint ""
		(layer "F.Cu")
		(at 479.478594 -117.77472)
		(property "Reference" "DB2"
			(at 1.686814 3.227578 0)
			(unlocked yes)
			(layer "F.SilkS")
			(effects
				(font
					(size 0.7874 0.5842)
					(thickness 0.1524)
				)
				(justify left)
			)
		)
		(property "Value" ""
			(at 0 0 0)
			(layer "F.Fab")
			(effects
				(font
					(size 1.27 1.27)
				)
			)
		)
		(duplicate_pad_numbers_are_jumpers no)
		(fp_line
			(start -3.330702 -4.771136)
			(end 3.330702 -4.771136)
			(stroke
				(width 0.1524)
				(type default)
			)
			(layer "F.SilkS")
		)
		(fp_line
			(start 0 4.011168)
			(end -3.330702 -4.771136)
			(stroke
				(width 0.1524)
				(type default)
			)
			(layer "F.SilkS")
		)
		(fp_line
			(start 3.330702 -4.771136)
			(end 0 4.011168)
			(stroke
				(width 0.1524)
				(type default)
			)
			(layer "F.SilkS")
		)
		(fp_line
			(start -3.330702 -4.771136)
			(end 3.330702 -4.771136)
			(stroke
				(width 0.1)
				(type default)
			)
			(layer "F.Fab")
		)
		(fp_line
			(start 0 4.011168)
			(end -3.330702 -4.771136)
			(stroke
				(width 0.1)
				(type default)
			)
			(layer "F.Fab")
		)
		(fp_line
			(start 3.330702 -4.771136)
			(end 0 4.011168)
			(stroke
				(width 0.1)
				(type default)
			)
			(layer "F.Fab")
		)
		(pad "1" thru_hole circle
			(at 0 0)
			(size 2.159 2.159)
			(drill 1.7018)
			(layers "*.Cu" "*.Mask")
			(remove_unused_layers no)
			(net "T1_GND")
			(clearance 0.0254)
			(thermal_gap 0.0254)
		)
		(pad "2" thru_hole circle
			(at -1.27 -3.348736)
			(size 2.159 2.159)
			(drill 1.7018)
			(layers "*.Cu" "*.Mask")
			(remove_unused_layers no)
			(net "TDR_SE_45_OHM_IN1")
			(clearance 0.0254)
			(thermal_gap 0.0254)
		)
		(pad "3" thru_hole circle
			(at 1.27 -3.348736)
			(size 2.159 2.159)
			(drill 1.7018)
			(layers "*.Cu" "*.Mask")
			(remove_unused_layers no)
			(net "TDR_SE_45_OHM_IN1")
			(clearance 0.0254)
			(thermal_gap 0.0254)
		)
	)
	(footprint ""
		(layer "F.Cu")
		(at 130.638296 -151.8793 90)
		(property "Reference" "PC353"
			(at 0 0 90)
			(layer "F.SilkS")
			(hide yes)
			(effects
				(font
					(size 1.27 1.27)
				)
			)
		)
		(property "Value" ""
			(at 0 0 90)
			(layer "F.Fab")
			(effects
				(font
					(size 1.27 1.27)
				)
			)
		)
		(duplicate_pad_numbers_are_jumpers no)
		(fp_line
			(start 0.7874 -0.4064)
			(end 0.7874 0.4064)
			(stroke
				(width 0.1524)
				(type default)
			)
			(layer "F.SilkS")
		)
		(fp_line
			(start -0.7874 -0.4064)
			(end 0.7874 -0.4064)
			(stroke
				(width 0.1524)
				(type default)
			)
			(layer "F.SilkS")
		)
		(fp_line
			(start 0.7874 0.4064)
			(end -0.7874 0.4064)
			(stroke
				(width 0.1524)
				(type default)
			)
			(layer "F.SilkS")
		)
		(fp_line
			(start -0.7874 0.4064)
			(end -0.7874 -0.4064)
			(stroke
				(width 0.1524)
				(type default)
			)
			(layer "F.SilkS")
		)
		(fp_line
			(start -0.12065 -0.305054)
			(end -0.12065 -0.2794)
			(stroke
				(width 0.1)
				(type default)
			)
			(layer "F.Fab")
		)
		(fp_line
			(start -0.67945 -0.305054)
			(end -0.12065 -0.305054)
			(stroke
				(width 0.1)
				(type default)
			)
			(layer "F.Fab")
		)
		(fp_line
			(start 0.67945 -0.3048)
			(end 0.67945 0.3048)
			(stroke
				(width 0.1)
				(type default)
			)
			(layer "F.Fab")
		)
		(fp_line
			(start 0.12065 -0.3048)
			(end 0.67945 -0.3048)
			(stroke
				(width 0.1)
				(type default)
			)
			(layer "F.Fab")
		)
		(fp_line
			(start 0.12065 -0.2794)
			(end 0.12065 -0.3048)
			(stroke
				(width 0.1)
				(type default)
			)
			(layer "F.Fab")
		)
		(fp_line
			(start -0.12065 -0.2794)
			(end 0.12065 -0.2794)
			(stroke
				(width 0.1)
				(type default)
			)
			(layer "F.Fab")
		)
		(fp_line
			(start 0.120396 0.2794)
			(end -0.12065 0.2794)
			(stroke
				(width 0.1)
				(type default)
			)
			(layer "F.Fab")
		)
		(fp_line
			(start -0.12065 0.2794)
			(end -0.12065 0.3048)
			(stroke
				(width 0.1)
				(type default)
			)
			(layer "F.Fab")
		)
		(fp_line
			(start 0.67945 0.3048)
			(end 0.120396 0.3048)
			(stroke
				(width 0.1)
				(type default)
			)
			(layer "F.Fab")
		)
		(fp_line
			(start 0.120396 0.3048)
			(end 0.120396 0.2794)
			(stroke
				(width 0.1)
				(type default)
			)
			(layer "F.Fab")
		)
		(fp_line
			(start -0.12065 0.3048)
			(end -0.67945 0.3048)
			(stroke
				(width 0.1)
				(type default)
			)
			(layer "F.Fab")
		)
		(fp_line
			(start -0.67945 0.3048)
			(end -0.67945 -0.305054)
			(stroke
				(width 0.1)
				(type default)
			)
			(layer "F.Fab")
		)
		(pad "1" smd circle
			(at -0.40005 0 90)
			(size 0 0)
			(layers "F.Cu" "F.Mask" "F.Paste")
			(net "SW_PVDDCR_SOC_P1_BOOT3_RC")
		)
		(pad "2" smd circle
			(at 0.40005 0 90)
			(size 0 0)
			(layers "F.Cu" "F.Mask" "F.Paste")
			(net "SW_PVDDCR_SOC_P1_PH3")
		)
	)
)
